(kicad_pcb
	(version 20260206)
	(generator "pcbnew")
	(generator_version "10.0")
	(general
		(thickness 1.6)
		(legacy_teardrops no)
	)
	(paper "A4")
	(title_block
		(title "01162023_DA0F0TEBIF0_F0T_Expander_BD_F_brd_V02_OCP.brd")
		(comment 1 "Grand Teton / footprints 2690-2696 of 9728")
	)
	(layers
		(0 "F.Cu" signal "TOP")
		(4 "In1.Cu" signal "GND")
		(6 "In2.Cu" signal "VCC")
		(8 "In3.Cu" signal "VCC1")
		(10 "In4.Cu" signal "GND1")
		(12 "In5.Cu" signal "IN1")
		(14 "In6.Cu" signal "GND2")
		(16 "In7.Cu" signal "IN2")
		(18 "In8.Cu" signal "GND3")
		(20 "In9.Cu" signal "IN3")
		(22 "In10.Cu" signal "GND4")
		(24 "In11.Cu" signal "IN4")
		(26 "In12.Cu" signal "GND5")
		(28 "In13.Cu" signal "IN5")
		(30 "In14.Cu" signal "GND6")
		(32 "In15.Cu" signal "IN6")
		(34 "In16.Cu" signal "GND7")
		(2 "B.Cu" signal "BOTTOM")
		(9 "F.Adhes" user "F.Adhesive")
		(11 "B.Adhes" user "B.Adhesive")
		(13 "F.Paste" user "Package Geometry/Pastemask Top")
		(15 "B.Paste" user "Package Geometry/Pastemask Bottom")
		(5 "F.SilkS" user "Ref Des/Silkscreen Top")
		(7 "B.SilkS" user "Ref Des/Silkscreen Bottom")
		(1 "F.Mask" user "Board Geometry/Soldermask Top")
		(3 "B.Mask" user "Board Geometry/Soldermask Bottom")
		(17 "Dwgs.User" user "User.Drawings")
		(19 "Cmts.User" user "User.Comments")
		(21 "Eco1.User" user "User.Eco1")
		(23 "Eco2.User" user "User.Eco2")
		(25 "Edge.Cuts" user "Board Geometry/Outline")
		(27 "Margin" user)
		(31 "F.CrtYd" user "Package Geometry/Place Bound Top")
		(29 "B.CrtYd" user "Package Geometry/Place Bound Bottom")
		(35 "F.Fab" user "Ref Des/Assembly Top")
		(33 "B.Fab" user "Ref Des/Assembly Bottom")
	)
	(footprint ""
		(layer "F.Cu")
		(at 17.926558 -25.432004 -90)
		(property "Reference" "C965"
			(at 0 0 270)
			(layer "F.SilkS")
			(hide yes)
			(effects
				(font
					(size 1.27 1.27)
				)
			)
		)
		(property "Value" ""
			(at 0 0 270)
			(layer "F.Fab")
			(effects
				(font
					(size 1.27 1.27)
				)
			)
		)
		(duplicate_pad_numbers_are_jumpers no)
		(fp_line
			(start -0.7874 0.4064)
			(end -0.7874 -0.4064)
			(stroke
				(width 0.1524)
				(type default)
			)
			(layer "F.SilkS")
		)
		(fp_line
			(start 0.7874 0.4064)
			(end -0.7874 0.4064)
			(stroke
				(width 0.1524)
				(type default)
			)
			(layer "F.SilkS")
		)
		(fp_line
			(start -0.7874 -0.4064)
			(end 0.7874 -0.4064)
			(stroke
				(width 0.1524)
				(type default)
			)
			(layer "F.SilkS")
		)
		(fp_line
			(start 0.7874 -0.4064)
			(end 0.7874 0.4064)
			(stroke
				(width 0.1524)
				(type default)
			)
			(layer "F.SilkS")
		)
		(fp_line
			(start -0.67945 0.3048)
			(end -0.67945 -0.305054)
			(stroke
				(width 0.1)
				(type default)
			)
			(layer "F.Fab")
		)
		(fp_line
			(start -0.12065 0.3048)
			(end -0.67945 0.3048)
			(stroke
				(width 0.1)
				(type default)
			)
			(layer "F.Fab")
		)
		(fp_line
			(start 0.120396 0.3048)
			(end 0.120396 0.2794)
			(stroke
				(width 0.1)
				(type default)
			)
			(layer "F.Fab")
		)
		(fp_line
			(start 0.67945 0.3048)
			(end 0.120396 0.3048)
			(stroke
				(width 0.1)
				(type default)
			)
			(layer "F.Fab")
		)
		(fp_line
			(start -0.12065 0.2794)
			(end -0.12065 0.3048)
			(stroke
				(width 0.1)
				(type default)
			)
			(layer "F.Fab")
		)
		(fp_line
			(start 0.120396 0.2794)
			(end -0.12065 0.2794)
			(stroke
				(width 0.1)
				(type default)
			)
			(layer "F.Fab")
		)
		(fp_line
			(start -0.12065 -0.2794)
			(end 0.12065 -0.2794)
			(stroke
				(width 0.1)
				(type default)
			)
			(layer "F.Fab")
		)
		(fp_line
			(start 0.12065 -0.2794)
			(end 0.12065 -0.3048)
			(stroke
				(width 0.1)
				(type default)
			)
			(layer "F.Fab")
		)
		(fp_line
			(start 0.12065 -0.3048)
			(end 0.67945 -0.3048)
			(stroke
				(width 0.1)
				(type default)
			)
			(layer "F.Fab")
		)
		(fp_line
			(start 0.67945 -0.3048)
			(end 0.67945 0.3048)
			(stroke
				(width 0.1)
				(type default)
			)
			(layer "F.Fab")
		)
		(fp_line
			(start -0.67945 -0.305054)
			(end -0.12065 -0.305054)
			(stroke
				(width 0.1)
				(type default)
			)
			(layer "F.Fab")
		)
		(fp_line
			(start -0.12065 -0.305054)
			(end -0.12065 -0.2794)
			(stroke
				(width 0.1)
				(type default)
			)
			(layer "F.Fab")
		)
		(pad "1" smd circle
			(at -0.40005 0 270)
			(size 0 0)
			(layers "F.Cu" "F.Mask" "F.Paste")
			(net "GND")
		)
		(pad "2" smd circle
			(at 0.40005 0 270)
			(size 0 0)
			(layers "F.Cu" "F.Mask" "F.Paste")
			(net "P3V3_SSD0")
		)
	)
	(footprint ""
		(layer "F.Cu")
		(at 334.518 -236.855 90)
		(property "Reference" "R1797"
			(at 0 0 90)
			(layer "F.SilkS")
			(hide yes)
			(effects
				(font
					(size 1.27 1.27)
				)
			)
		)
		(property "Value" ""
			(at 0 0 90)
			(layer "F.Fab")
			(effects
				(font
					(size 1.27 1.27)
				)
			)
		)
		(duplicate_pad_numbers_are_jumpers no)
		(fp_line
			(start 0.7874 -0.4064)
			(end 0.7874 0.4064)
			(stroke
				(width 0.1524)
				(type default)
			)
			(layer "F.SilkS")
		)
		(fp_line
			(start -0.7874 -0.4064)
			(end 0.7874 -0.4064)
			(stroke
				(width 0.1524)
				(type default)
			)
			(layer "F.SilkS")
		)
		(fp_line
			(start 0.7874 0.4064)
			(end -0.7874 0.4064)
			(stroke
				(width 0.1524)
				(type default)
			)
			(layer "F.SilkS")
		)
		(fp_line
			(start -0.7874 0.4064)
			(end -0.7874 -0.4064)
			(stroke
				(width 0.1524)
				(type default)
			)
			(layer "F.SilkS")
		)
		(fp_line
			(start -0.12065 -0.305054)
			(end -0.12065 -0.2794)
			(stroke
				(width 0.1)
				(type default)
			)
			(layer "F.Fab")
		)
		(fp_line
			(start -0.67945 -0.305054)
			(end -0.12065 -0.305054)
			(stroke
				(width 0.1)
				(type default)
			)
			(layer "F.Fab")
		)
		(fp_line
			(start 0.67945 -0.3048)
			(end 0.67945 0.3048)
			(stroke
				(width 0.1)
				(type default)
			)
			(layer "F.Fab")
		)
		(fp_line
			(start 0.12065 -0.3048)
			(end 0.67945 -0.3048)
			(stroke
				(width 0.1)
				(type default)
			)
			(layer "F.Fab")
		)
		(fp_line
			(start 0.12065 -0.2794)
			(end 0.12065 -0.3048)
			(stroke
				(width 0.1)
				(type default)
			)
			(layer "F.Fab")
		)
		(fp_line
			(start -0.12065 -0.2794)
			(end 0.12065 -0.2794)
			(stroke
				(width 0.1)
				(type default)
			)
			(layer "F.Fab")
		)
		(fp_line
			(start 0.120396 0.2794)
			(end -0.12065 0.2794)
			(stroke
				(width 0.1)
				(type default)
			)
			(layer "F.Fab")
		)
		(fp_line
			(start -0.12065 0.2794)
			(end -0.12065 0.3048)
			(stroke
				(width 0.1)
				(type default)
			)
			(layer "F.Fab")
		)
		(fp_line
			(start 0.67945 0.3048)
			(end 0.120396 0.3048)
			(stroke
				(width 0.1)
				(type default)
			)
			(layer "F.Fab")
		)
		(fp_line
			(start 0.120396 0.3048)
			(end 0.120396 0.2794)
			(stroke
				(width 0.1)
				(type default)
			)
			(layer "F.Fab")
		)
		(fp_line
			(start -0.12065 0.3048)
			(end -0.67945 0.3048)
			(stroke
				(width 0.1)
				(type default)
			)
			(layer "F.Fab")
		)
		(fp_line
			(start -0.67945 0.3048)
			(end -0.67945 -0.305054)
			(stroke
				(width 0.1)
				(type default)
			)
			(layer "F.Fab")
		)
		(pad "1" smd circle
			(at -0.40005 0 90)
			(size 0 0)
			(layers "F.Cu" "F.Mask" "F.Paste")
			(net "MB_SWB_PWRGD")
		)
		(pad "2" smd circle
			(at 0.40005 0 90)
			(size 0 0)
			(layers "F.Cu" "F.Mask" "F.Paste")
			(net "MB_SWB_PWRGD_R")
		)
	)
	(footprint ""
		(layer "F.Cu")
		(at 316.500764 -343.952322 90)
		(property "Reference" "C548"
			(at 0 0 90)
			(layer "F.SilkS")
			(hide yes)
			(effects
				(font
					(size 1.27 1.27)
				)
			)
		)
		(property "Value" ""
			(at 0 0 90)
			(layer "F.Fab")
			(effects
				(font
					(size 1.27 1.27)
				)
			)
		)
		(duplicate_pad_numbers_are_jumpers no)
		(fp_line
			(start 0.299974 -0.150114)
			(end 0.299974 0.150114)
			(stroke
				(width 0.1)
				(type default)
			)
			(layer "F.Fab")
		)
		(fp_line
			(start -0.299974 -0.150114)
			(end 0.299974 -0.150114)
			(stroke
				(width 0.1)
				(type default)
			)
			(layer "F.Fab")
		)
		(fp_line
			(start 0.299974 0.150114)
			(end -0.299974 0.150114)
			(stroke
				(width 0.1)
				(type default)
			)
			(layer "F.Fab")
		)
		(fp_line
			(start -0.299974 0.150114)
			(end -0.299974 -0.150114)
			(stroke
				(width 0.1)
				(type default)
			)
			(layer "F.Fab")
		)
		(pad "1" smd rect
			(at -0.2667 0 90)
			(size 0.3048 0.381)
			(layers "F.Cu" "F.Mask" "F.Paste")
			(net "P5E_PEX2_STN5_TX_DN<81>")
		)
		(pad "2" smd rect
			(at 0.2667 0 90)
			(size 0.3048 0.381)
			(layers "F.Cu" "F.Mask" "F.Paste")
			(net "P5E_PEX2_STN5_TX_C_DN<81>")
		)
	)
	(footprint ""
		(layer "F.Cu")
		(at 447.275712 -119.477028 180)
		(property "Reference" "R885"
			(at 0 0 180)
			(layer "F.SilkS")
			(hide yes)
			(effects
				(font
					(size 1.27 1.27)
				)
			)
		)
		(property "Value" ""
			(at 0 0 180)
			(layer "F.Fab")
			(effects
				(font
					(size 1.27 1.27)
				)
			)
		)
		(duplicate_pad_numbers_are_jumpers no)
		(fp_line
			(start 0.7874 0.4064)
			(end -0.7874 0.4064)
			(stroke
				(width 0.1524)
				(type default)
			)
			(layer "F.SilkS")
		)
		(fp_line
			(start 0.7874 -0.4064)
			(end 0.7874 0.4064)
			(stroke
				(width 0.1524)
				(type default)
			)
			(layer "F.SilkS")
		)
		(fp_line
			(start -0.7874 0.4064)
			(end -0.7874 -0.4064)
			(stroke
				(width 0.1524)
				(type default)
			)
			(layer "F.SilkS")
		)
		(fp_line
			(start -0.7874 -0.4064)
			(end 0.7874 -0.4064)
			(stroke
				(width 0.1524)
				(type default)
			)
			(layer "F.SilkS")
		)
		(fp_line
			(start 0.67945 0.3048)
			(end 0.120396 0.3048)
			(stroke
				(width 0.1)
				(type default)
			)
			(layer "F.Fab")
		)
		(fp_line
			(start 0.67945 -0.3048)
			(end 0.67945 0.3048)
			(stroke
				(width 0.1)
				(type default)
			)
			(layer "F.Fab")
		)
		(fp_line
			(start 0.12065 -0.2794)
			(end 0.12065 -0.3048)
			(stroke
				(width 0.1)
				(type default)
			)
			(layer "F.Fab")
		)
		(fp_line
			(start 0.12065 -0.3048)
			(end 0.67945 -0.3048)
			(stroke
				(width 0.1)
				(type default)
			)
			(layer "F.Fab")
		)
		(fp_line
			(start 0.120396 0.3048)
			(end 0.120396 0.2794)
			(stroke
				(width 0.1)
				(type default)
			)
			(layer "F.Fab")
		)
		(fp_line
			(start 0.120396 0.2794)
			(end -0.12065 0.2794)
			(stroke
				(width 0.1)
				(type default)
			)
			(layer "F.Fab")
		)
		(fp_line
			(start -0.12065 0.3048)
			(end -0.67945 0.3048)
			(stroke
				(width 0.1)
				(type default)
			)
			(layer "F.Fab")
		)
		(fp_line
			(start -0.12065 0.2794)
			(end -0.12065 0.3048)
			(stroke
				(width 0.1)
				(type default)
			)
			(layer "F.Fab")
		)
		(fp_line
			(start -0.12065 -0.2794)
			(end 0.12065 -0.2794)
			(stroke
				(width 0.1)
				(type default)
			)
			(layer "F.Fab")
		)
		(fp_line
			(start -0.12065 -0.305054)
			(end -0.12065 -0.2794)
			(stroke
				(width 0.1)
				(type default)
			)
			(layer "F.Fab")
		)
		(fp_line
			(start -0.67945 0.3048)
			(end -0.67945 -0.305054)
			(stroke
				(width 0.1)
				(type default)
			)
			(layer "F.Fab")
		)
		(fp_line
			(start -0.67945 -0.305054)
			(end -0.12065 -0.305054)
			(stroke
				(width 0.1)
				(type default)
			)
			(layer "F.Fab")
		)
		(pad "1" smd circle
			(at -0.40005 0 180)
			(size 0 0)
			(layers "F.Cu" "F.Mask" "F.Paste")
			(net "P3V3_NIC7")
		)
		(pad "2" smd circle
			(at 0.40005 0 180)
			(size 0 0)
			(layers "F.Cu" "F.Mask" "F.Paste")
			(net "PWRGD_P3V3_NIC7")
		)
	)
	(footprint ""
		(layer "F.Cu")
		(at 261.34187 -242.372388 180)
		(property "Reference" "R6582"
			(at 0 0 180)
			(layer "F.SilkS")
			(hide yes)
			(effects
				(font
					(size 1.27 1.27)
				)
			)
		)
		(property "Value" ""
			(at 0 0 180)
			(layer "F.Fab")
			(effects
				(font
					(size 1.27 1.27)
				)
			)
		)
		(duplicate_pad_numbers_are_jumpers no)
		(fp_line
			(start 0.7874 0.4064)
			(end -0.7874 0.4064)
			(stroke
				(width 0.1524)
				(type default)
			)
			(layer "F.SilkS")
		)
		(fp_line
			(start 0.7874 -0.4064)
			(end 0.7874 0.4064)
			(stroke
				(width 0.1524)
				(type default)
			)
			(layer "F.SilkS")
		)
		(fp_line
			(start -0.7874 0.4064)
			(end -0.7874 -0.4064)
			(stroke
				(width 0.1524)
				(type default)
			)
			(layer "F.SilkS")
		)
		(fp_line
			(start -0.7874 -0.4064)
			(end 0.7874 -0.4064)
			(stroke
				(width 0.1524)
				(type default)
			)
			(layer "F.SilkS")
		)
		(fp_line
			(start 0.67945 0.3048)
			(end 0.120396 0.3048)
			(stroke
				(width 0.1)
				(type default)
			)
			(layer "F.Fab")
		)
		(fp_line
			(start 0.67945 -0.3048)
			(end 0.67945 0.3048)
			(stroke
				(width 0.1)
				(type default)
			)
			(layer "F.Fab")
		)
		(fp_line
			(start 0.12065 -0.2794)
			(end 0.12065 -0.3048)
			(stroke
				(width 0.1)
				(type default)
			)
			(layer "F.Fab")
		)
		(fp_line
			(start 0.12065 -0.3048)
			(end 0.67945 -0.3048)
			(stroke
				(width 0.1)
				(type default)
			)
			(layer "F.Fab")
		)
		(fp_line
			(start 0.120396 0.3048)
			(end 0.120396 0.2794)
			(stroke
				(width 0.1)
				(type default)
			)
			(layer "F.Fab")
		)
		(fp_line
			(start 0.120396 0.2794)
			(end -0.12065 0.2794)
			(stroke
				(width 0.1)
				(type default)
			)
			(layer "F.Fab")
		)
		(fp_line
			(start -0.12065 0.3048)
			(end -0.67945 0.3048)
			(stroke
				(width 0.1)
				(type default)
			)
			(layer "F.Fab")
		)
		(fp_line
			(start -0.12065 0.2794)
			(end -0.12065 0.3048)
			(stroke
				(width 0.1)
				(type default)
			)
			(layer "F.Fab")
		)
		(fp_line
			(start -0.12065 -0.2794)
			(end 0.12065 -0.2794)
			(stroke
				(width 0.1)
				(type default)
			)
			(layer "F.Fab")
		)
		(fp_line
			(start -0.12065 -0.305054)
			(end -0.12065 -0.2794)
			(stroke
				(width 0.1)
				(type default)
			)
			(layer "F.Fab")
		)
		(fp_line
			(start -0.67945 0.3048)
			(end -0.67945 -0.305054)
			(stroke
				(width 0.1)
				(type default)
			)
			(layer "F.Fab")
		)
		(fp_line
			(start -0.67945 -0.305054)
			(end -0.12065 -0.305054)
			(stroke
				(width 0.1)
				(type default)
			)
			(layer "F.Fab")
		)
		(pad "1" smd circle
			(at -0.40005 0 180)
			(size 0 0)
			(layers "F.Cu" "F.Mask" "F.Paste")
			(net "PWRGD_PEX2_P1V8_PLL_R")
		)
		(pad "2" smd circle
			(at 0.40005 0 180)
			(size 0 0)
			(layers "F.Cu" "F.Mask" "F.Paste")
			(net "PWRGD_PEX2_P1V8_PLL")
		)
	)
	(footprint ""
		(layer "F.Cu")
		(at 420.03853 -44.341542 90)
		(property "Reference" "C405"
			(at 0 0 90)
			(layer "F.SilkS")
			(hide yes)
			(effects
				(font
					(size 1.27 1.27)
				)
			)
		)
		(property "Value" ""
			(at 0 0 90)
			(layer "F.Fab")
			(effects
				(font
					(size 1.27 1.27)
				)
			)
		)
		(duplicate_pad_numbers_are_jumpers no)
		(fp_line
			(start 0.7874 -0.4064)
			(end 0.7874 0.4064)
			(stroke
				(width 0.1524)
				(type default)
			)
			(layer "F.SilkS")
		)
		(fp_line
			(start -0.7874 -0.4064)
			(end 0.7874 -0.4064)
			(stroke
				(width 0.1524)
				(type default)
			)
			(layer "F.SilkS")
		)
		(fp_line
			(start 0.7874 0.4064)
			(end -0.7874 0.4064)
			(stroke
				(width 0.1524)
				(type default)
			)
			(layer "F.SilkS")
		)
		(fp_line
			(start -0.7874 0.4064)
			(end -0.7874 -0.4064)
			(stroke
				(width 0.1524)
				(type default)
			)
			(layer "F.SilkS")
		)
		(fp_line
			(start -0.12065 -0.305054)
			(end -0.12065 -0.2794)
			(stroke
				(width 0.1)
				(type default)
			)
			(layer "F.Fab")
		)
		(fp_line
			(start -0.67945 -0.305054)
			(end -0.12065 -0.305054)
			(stroke
				(width 0.1)
				(type default)
			)
			(layer "F.Fab")
		)
		(fp_line
			(start 0.67945 -0.3048)
			(end 0.67945 0.3048)
			(stroke
				(width 0.1)
				(type default)
			)
			(layer "F.Fab")
		)
		(fp_line
			(start 0.12065 -0.3048)
			(end 0.67945 -0.3048)
			(stroke
				(width 0.1)
				(type default)
			)
			(layer "F.Fab")
		)
		(fp_line
			(start 0.12065 -0.2794)
			(end 0.12065 -0.3048)
			(stroke
				(width 0.1)
				(type default)
			)
			(layer "F.Fab")
		)
		(fp_line
			(start -0.12065 -0.2794)
			(end 0.12065 -0.2794)
			(stroke
				(width 0.1)
				(type default)
			)
			(layer "F.Fab")
		)
		(fp_line
			(start 0.120396 0.2794)
			(end -0.12065 0.2794)
			(stroke
				(width 0.1)
				(type default)
			)
			(layer "F.Fab")
		)
		(fp_line
			(start -0.12065 0.2794)
			(end -0.12065 0.3048)
			(stroke
				(width 0.1)
				(type default)
			)
			(layer "F.Fab")
		)
		(fp_line
			(start 0.67945 0.3048)
			(end 0.120396 0.3048)
			(stroke
				(width 0.1)
				(type default)
			)
			(layer "F.Fab")
		)
		(fp_line
			(start 0.120396 0.3048)
			(end 0.120396 0.2794)
			(stroke
				(width 0.1)
				(type default)
			)
			(layer "F.Fab")
		)
		(fp_line
			(start -0.12065 0.3048)
			(end -0.67945 0.3048)
			(stroke
				(width 0.1)
				(type default)
			)
			(layer "F.Fab")
		)
		(fp_line
			(start -0.67945 0.3048)
			(end -0.67945 -0.305054)
			(stroke
				(width 0.1)
				(type default)
			)
			(layer "F.Fab")
		)
		(pad "1" smd circle
			(at -0.40005 0 90)
			(size 0 0)
			(layers "F.Cu" "F.Mask" "F.Paste")
			(net "P12V_SSD14_VIN_P")
		)
		(pad "2" smd circle
			(at 0.40005 0 90)
			(size 0 0)
			(layers "F.Cu" "F.Mask" "F.Paste")
			(net "P12V_SSD14_VIN_N")
		)
	)
	(footprint ""
		(layer "F.Cu")
		(at 163.63061 -66.32194 -90)
		(property "Reference" "PC847"
			(at 0 0 270)
			(layer "F.SilkS")
			(hide yes)
			(effects
				(font
					(size 1.27 1.27)
				)
			)
		)
		(property "Value" ""
			(at 0 0 270)
			(layer "F.Fab")
			(effects
				(font
					(size 1.27 1.27)
				)
			)
		)
		(duplicate_pad_numbers_are_jumpers no)
		(fp_line
			(start -0.7874 0.4064)
			(end -0.7874 -0.4064)
			(stroke
				(width 0.1524)
				(type default)
			)
			(layer "F.SilkS")
		)
		(fp_line
			(start 0.7874 0.4064)
			(end -0.7874 0.4064)
			(stroke
				(width 0.1524)
				(type default)
			)
			(layer "F.SilkS")
		)
		(fp_line
			(start -0.7874 -0.4064)
			(end 0.7874 -0.4064)
			(stroke
				(width 0.1524)
				(type default)
			)
			(layer "F.SilkS")
		)
		(fp_line
			(start 0.7874 -0.4064)
			(end 0.7874 0.4064)
			(stroke
				(width 0.1524)
				(type default)
			)
			(layer "F.SilkS")
		)
		(fp_line
			(start -0.67945 0.3048)
			(end -0.67945 -0.305054)
			(stroke
				(width 0.1)
				(type default)
			)
			(layer "F.Fab")
		)
		(fp_line
			(start -0.12065 0.3048)
			(end -0.67945 0.3048)
			(stroke
				(width 0.1)
				(type default)
			)
			(layer "F.Fab")
		)
		(fp_line
			(start 0.120396 0.3048)
			(end 0.120396 0.2794)
			(stroke
				(width 0.1)
				(type default)
			)
			(layer "F.Fab")
		)
		(fp_line
			(start 0.67945 0.3048)
			(end 0.120396 0.3048)
			(stroke
				(width 0.1)
				(type default)
			)
			(layer "F.Fab")
		)
		(fp_line
			(start -0.12065 0.2794)
			(end -0.12065 0.3048)
			(stroke
				(width 0.1)
				(type default)
			)
			(layer "F.Fab")
		)
		(fp_line
			(start 0.120396 0.2794)
			(end -0.12065 0.2794)
			(stroke
				(width 0.1)
				(type default)
			)
			(layer "F.Fab")
		)
		(fp_line
			(start -0.12065 -0.2794)
			(end 0.12065 -0.2794)
			(stroke
				(width 0.1)
				(type default)
			)
			(layer "F.Fab")
		)
		(fp_line
			(start 0.12065 -0.2794)
			(end 0.12065 -0.3048)
			(stroke
				(width 0.1)
				(type default)
			)
			(layer "F.Fab")
		)
		(fp_line
			(start 0.12065 -0.3048)
			(end 0.67945 -0.3048)
			(stroke
				(width 0.1)
				(type default)
			)
			(layer "F.Fab")
		)
		(fp_line
			(start 0.67945 -0.3048)
			(end 0.67945 0.3048)
			(stroke
				(width 0.1)
				(type default)
			)
			(layer "F.Fab")
		)
		(fp_line
			(start -0.67945 -0.305054)
			(end -0.12065 -0.305054)
			(stroke
				(width 0.1)
				(type default)
			)
			(layer "F.Fab")
		)
		(fp_line
			(start -0.12065 -0.305054)
			(end -0.12065 -0.2794)
			(stroke
				(width 0.1)
				(type default)
			)
			(layer "F.Fab")
		)
		(pad "1" smd circle
			(at -0.40005 0 270)
			(size 0 0)
			(layers "F.Cu" "F.Mask" "F.Paste")
			(net "P12V_SSD5_CO_DV_DT")
		)
		(pad "2" smd circle
			(at 0.40005 0 270)
			(size 0 0)
			(layers "F.Cu" "F.Mask" "F.Paste")
			(net "GND")
		)
	)
)
